# T6G (Grand Teton) — schematic netlist excerpt (pin names and nets, part order shuffled) for the footprints in the layout excerpt that follows; sources: Cadence DE-HDL packaged netlist, KiCad conversion of 04192023_DAF0TMB3IC0_F0TG_MB_C_brd_V02_OCP.brd

J18  SCONN288_DDR506112002KQ  IO  pkg DDR288S_1-1VXC  page 94
  VIN_BULK0  = P12V_MEM_CPU0
  RFU0  = NC
  VIN_MGMT  = P3V3_AUX
  HSCL  = I3C_SPD_DDRI_CPU0_SCL
  HSDA  = I3C_SPD_DDRI_CPU0_SDA
  VSS0  = GND
  DQ0_A  = M_I_CPU0_SA_DQ<0>
  VSS1  = GND
  DQ1_A  = M_I_CPU0_SA_DQ<1>
  VSS2  = GND
  DQS0_A_T  = M_I_CPU0_SA_DQS_DP<0>
  DQS0_A_C  = M_I_CPU0_SA_DQS_DN<0>
  VSS3  = GND
  DQ4_A  = M_I_CPU0_SA_DQ<4>
  VSS4  = GND
  DQ5_A  = M_I_CPU0_SA_DQ<5>
  VSS5  = GND
  DQ8_A  = M_I_CPU0_SA_DQ<8>
  VSS6  = GND
  DQ9_A  = M_I_CPU0_SA_DQ<9>
  VSS7  = GND
  DQS1_A_T  = M_I_CPU0_SA_DQS_DP<1>
  DQS1_A_C  = M_I_CPU0_SA_DQS_DN<1>
  VSS8  = GND
  DQ12_A  = M_I_CPU0_SA_DQ<12>
  VSS9  = GND
  DQ13_A  = M_I_CPU0_SA_DQ<13>
  VSS10  = GND
  DQ16_A  = M_I_CPU0_SA_DQ<16>
  VSS11  = GND
  DQ17_A  = M_I_CPU0_SA_DQ<17>
  VSS12  = GND
  DQS2_A_T  = M_I_CPU0_SA_DQS_DP<2>
  DQS2_A_C  = M_I_CPU0_SA_DQS_DN<2>
  VSS13  = GND
  DQ20_A  = M_I_CPU0_SA_DQ<20>
  VSS14  = GND
  DQ21_A  = M_I_CPU0_SA_DQ<21>
  VSS15  = GND
  DQ24_A  = M_I_CPU0_SA_DQ<24>
  VSS16  = GND
  DQ25_A  = M_I_CPU0_SA_DQ<25>
  VSS17  = GND
  DQS3_A_T  = M_I_CPU0_SA_DQS_DP<3>
  DQS3_A_C  = M_I_CPU0_SA_DQS_DN<3>
  VSS18  = GND
  DQ28_A  = M_I_CPU0_SA_DQ<28>
  VSS19  = GND
  DQ29_A  = M_I_CPU0_SA_DQ<29>
  VSS20  = GND
  CB0_A  = M_I_CPU0_SA_CB<0>
  VSS21  = GND
  CB1_A  = M_I_CPU0_SA_CB<1>
  VSS22  = GND
  DQS4_A_T  = M_I_CPU0_SA_DQS_DP<4>
  DQS4_A_C  = M_I_CPU0_SA_DQS_DN<4>
  VSS23  = GND
  CB4_A  = M_I_CPU0_SA_CB<4>
  VSS24  = GND
  CB5_A  = M_I_CPU0_SA_CB<5>
  VSS25  = GND
  ALERT_N  = M_I_CPU0_ALERT_N
  VSS26  = GND
  CS0_A_N  = M_I_CPU0_SA_CS_N<0>
  VSS27  = GND
  CA0_A  = M_I_CPU0_SA_CA<0>
  VSS28  = GND
  CA2_A  = M_I_CPU0_SA_CA<2>
  VSS29  = GND
  CA4_A  = M_I_CPU0_SA_CA<4>
  VSS30  = GND
  CA6_A  = M_I_CPU0_SA_CA<6>
  VSS31  = GND
  PAR_A  = M_I_CPU0_SA_PAR
  VSS32  = GND
  CA0_B  = M_I_CPU0_SB_CA<0>
  VSS33  = GND
  CA2_B  = M_I_CPU0_SB_CA<2>
  VSS34  = GND
  CA4_B  = M_I_CPU0_SB_CA<4>
  VSS35  = GND
  CA6_B  = M_I_CPU0_SB_CA<6>
  VSS36  = GND
  CS0_B_N  = M_I_CPU0_SB_CS_N<0>
  VSS37  = GND
  \lbd||rsp_a_n\  = M_I_CPU0_SA_RSP<0>
  \lbs||rsp_b_n\  = M_I_CPU0_SB_RSP<0>
  VSS38  = GND
  CB4_B  = M_I_CPU0_SB_CB<4>
  VSS39  = GND
  CB5_B  = M_I_CPU0_SB_CB<5>
  VSS40  = GND
  \dqs9_b_t||tdqs9_b_t||dbi4_b_n\  = M_I_CPU0_SB_DQS_DP<9>
  \dqs9_b_c||tdqs9_b_c\  = M_I_CPU0_SB_DQS_DN<9>
  VSS41  = GND
  CB0_B  = M_I_CPU0_SB_CB<0>
  VSS42  = GND
  CB1_B  = M_I_CPU0_SB_CB<1>
  VSS43  = GND
  DQ0_B  = M_I_CPU0_SB_DQ<0>
  VSS44  = GND
  DQ1_B  = M_I_CPU0_SB_DQ<1>
  VSS45  = GND
  DQS0_B_T  = M_I_CPU0_SB_DQS_DP<0>
  DQS0_B_C  = M_I_CPU0_SB_DQS_DN<0>
  VSS46  = GND
  DQ4_B  = M_I_CPU0_SB_DQ<4>
  VSS47  = GND
  DQ5_B  = M_I_CPU0_SB_DQ<5>
  VSS48  = GND
  DQ8_B  = M_I_CPU0_SB_DQ<8>
  VSS49  = GND
  DQ9_B  = M_I_CPU0_SB_DQ<9>
  VSS50  = GND
  DQS1_B_T  = M_I_CPU0_SB_DQS_DP<1>
  DQS1_B_C  = M_I_CPU0_SB_DQS_DN<1>
  VSS51  = GND
  DQ12_B  = M_I_CPU0_SB_DQ<12>
  VSS52  = GND
  DQ13_B  = M_I_CPU0_SB_DQ<13>
  VSS53  = GND
  DQ16_B  = M_I_CPU0_SB_DQ<16>
  VSS54  = GND
  DQ17_B  = M_I_CPU0_SB_DQ<17>
  VSS55  = GND
  DQS2_B_T  = M_I_CPU0_SB_DQS_DP<2>
  DQS2_B_C  = M_I_CPU0_SB_DQS_DN<2>
  VSS56  = GND
  DQ20_B  = M_I_CPU0_SB_DQ<20>
  VSS57  = GND
  DQ21_B  = M_I_CPU0_SB_DQ<21>
  VSS58  = GND
  DQ24_B  = M_I_CPU0_SB_DQ<24>
  VSS59  = GND
  DQ25_B  = M_I_CPU0_SB_DQ<25>
  VSS60  = GND
  DQS3_B_T  = M_I_CPU0_SB_DQS_DP<3>
  DQS3_B_C  = M_I_CPU0_SB_DQS_DN<3>
  VSS61  = GND
  DQ28_B  = M_I_CPU0_SB_DQ<28>
  VSS62  = GND
  DQ29_B  = M_I_CPU0_SB_DQ<29>
  VSS63  = GND
  RFU1  = NC
  VIN_BULK1  = P12V_MEM_CPU0
  VIN_BULK2  = P12V_MEM_CPU0
  \pwr_good||fail_n\  = PWRGD_CHI_CPU0_DIMM
  HAS  = PD_CHI_CPU0_DIMM_SAA
  RFU2  = NC
  RFU3  = NC
  VSS64  = GND
  DQ2_A  = M_I_CPU0_SA_DQ<2>
  VSS65  = GND
  DQ3_A  = M_I_CPU0_SA_DQ<3>
  VSS66  = GND
  \dqs5_a_c||tdqs5_a_c||dqs5_a_t||tdqs5_a_t\  = M_I_CPU0_SA_DQS_DN<5>
  \dqs5_a_t||tdqs5_a_t\  = M_I_CPU0_SA_DQS_DP<5>
  VSS67  = GND
  DQ6_A  = M_I_CPU0_SA_DQ<6>
  VSS68  = GND
  DQ7_A  = M_I_CPU0_SA_DQ<7>
  VSS69  = GND
  DQ10_A  = M_I_CPU0_SA_DQ<10>
  VSS70  = GND
  DQ11_A  = M_I_CPU0_SA_DQ<11>
  VSS71  = GND
  \dqs6_a_c||tdqs6_a_c||dqs6_a_t||tdqs6_a_t\  = M_I_CPU0_SA_DQS_DN<6>
  \dqs6_a_t||tdqs6_a_t\  = M_I_CPU0_SA_DQS_DP<6>
  VSS72  = GND
  DQ14_A  = M_I_CPU0_SA_DQ<14>
  VSS73  = GND
  DQ15_A  = M_I_CPU0_SA_DQ<15>
  VSS74  = GND
  DQ18_A  = M_I_CPU0_SA_DQ<18>
  VSS75  = GND
  DQ19_A  = M_I_CPU0_SA_DQ<19>
  VSS76  = GND
  \dqs7_a_c||tdqs7_a_c\  = M_I_CPU0_SA_DQS_DN<7>
  \dqs7_a_t||tdqs7_a_t\  = M_I_CPU0_SA_DQS_DP<7>
  VSS77  = GND
  DQ22_A  = M_I_CPU0_SA_DQ<22>
  VSS78  = GND
  DQ23_A  = M_I_CPU0_SA_DQ<23>
  VSS79  = GND
  DQ26_A  = M_I_CPU0_SA_DQ<26>
  VSS80  = GND
  DQ27_A  = M_I_CPU0_SA_DQ<27>
  VSS81  = GND
  \dqs8_a_c||tdqs8_a_c\  = M_I_CPU0_SA_DQS_DN<8>
  \dqs8_a_t||tdqs8_a_t\  = M_I_CPU0_SA_DQS_DP<8>
  VSS82  = GND
  DQ30_A  = M_I_CPU0_SA_DQ<30>
  VSS83  = GND
  DQ31_A  = M_I_CPU0_SA_DQ<31>
  VSS84  = GND
  CB2_A  = M_I_CPU0_SA_CB<2>
  VSS85  = GND
  CB3_A  = M_I_CPU0_SA_CB<3>
  VSS86  = GND
  \dqs9_a_c||tdqs9_a_c\  = M_I_CPU0_SA_DQS_DN<9>
  \dqs9_a_t||tdqs9_a_t\  = M_I_CPU0_SA_DQS_DP<9>
  VSS87  = GND
  CB6_A  = M_I_CPU0_SA_CB<6>
  VSS88  = GND
  CB7_A  = M_I_CPU0_SA_CB<7>
  VSS89  = GND
  RESET_N  = M_I_CPU0_RESET_N
  VSS90  = GND
  CS1_A_N  = M_I_CPU0_SA_CS_N<1>
  VSS91  = GND
  CA1_A  = M_I_CPU0_SA_CA<1>
  VSS92  = GND
  CA3_A  = M_I_CPU0_SA_CA<3>
  VSS93  = GND
  CA5_A  = M_I_CPU0_SA_CA<5>
  VSS94  = GND
  CK_T  = M_I_CPU0_CLK_DP<0>
  CK_C  = M_I_CPU0_CLK_DN<0>
  VSS95  = GND
  RFU4  = NC
  CA1_B  = M_I_CPU0_SB_CA<1>
  VSS96  = GND
  CA3_B  = M_I_CPU0_SB_CA<3>
  VSS97  = GND
  CA5_B  = M_I_CPU0_SB_CA<5>
  VSS98  = GND
  PAR_B  = M_I_CPU0_SB_PAR
  VSS99  = GND
  CS1_B_N  = M_I_CPU0_SB_CS_N<1>
  VSS100  = GND
  RFU5  = NC
  RFU6  = NC
  VSS101  = GND
  CB6_B  = M_I_CPU0_SB_CB<6>
  VSS102  = GND
  CB7_B  = M_I_CPU0_SB_CB<7>
  VSS103  = GND
  DQS4_B_C  = M_I_CPU0_SB_DQS_DN<4>
  DQS4_B_T  = M_I_CPU0_SB_DQS_DP<4>
  VSS104  = GND
  CB2_B  = M_I_CPU0_SB_CB<2>
  VSS105  = GND
  CB3_B  = M_I_CPU0_SB_CB<3>
  VSS106  = GND
  DQ2_B  = M_I_CPU0_SB_DQ<2>
  VSS107  = GND
  DQ3_B  = M_I_CPU0_SB_DQ<3>
  VSS108  = GND
  \dqs5_b_c||tdqs5_b_c\  = M_I_CPU0_SB_DQS_DN<5>
  \dqs5_b_t||tdqs5_b_t\  = M_I_CPU0_SB_DQS_DP<5>
  VSS109  = GND
  DQ6_B  = M_I_CPU0_SB_DQ<6>
  VSS110  = GND
  DQ7_B  = M_I_CPU0_SB_DQ<7>
  VSS111  = GND
  DQ10_B  = M_I_CPU0_SB_DQ<10>
  VSS112  = GND
  DQ11_B  = M_I_CPU0_SB_DQ<11>
  VSS113  = GND
  \dqs6_b_c||tdqs6_b_c\  = M_I_CPU0_SB_DQS_DN<6>
  \dqs6_b_t||tdqs6_b_t\  = M_I_CPU0_SB_DQS_DP<6>
  VSS114  = GND
  DQ14_B  = M_I_CPU0_SB_DQ<14>
  VSS115  = GND
  DQ15_B  = M_I_CPU0_SB_DQ<15>
  VSS116  = GND
  DQ18_B  = M_I_CPU0_SB_DQ<18>
  VSS117  = GND
  DQ19_B  = M_I_CPU0_SB_DQ<19>
  VSS118  = GND
  \dqs7_b_c||tdqs7_b_c\  = M_I_CPU0_SB_DQS_DN<7>
  \dqs7_b_t||tdqs7_b_t\  = M_I_CPU0_SB_DQS_DP<7>
  VSS119  = GND
  DQ22_B  = M_I_CPU0_SB_DQ<22>
  VSS120  = GND
  DQ23_B  = M_I_CPU0_SB_DQ<23>
  VSS121  = GND
  DQ26_B  = M_I_CPU0_SB_DQ<26>
  VSS122  = GND
  DQ27_B  = M_I_CPU0_SB_DQ<27>
  VSS123  = GND
  \dqs8_b_c||tdqs8_b_c\  = M_I_CPU0_SB_DQS_DN<8>
  \dqs8_b_t||tdqs8_b_t\  = M_I_CPU0_SB_DQS_DP<8>
  VSS124  = GND
  DQ30_B  = M_I_CPU0_SB_DQ<30>
  VSS125  = GND
  DQ31_B  = M_I_CPU0_SB_DQ<31>
  VSS126  = GND
  G1  = GND
  G2  = GND
  G3  = GND

(kicad_pcb
	(version 20260206)
	(generator "pcbnew")
	(generator_version "10.0")
	(general
		(thickness 1.6)
		(legacy_teardrops no)
	)
	(paper "A4")
	(title_block
		(title "04192023_DAF0TMB3IC0_F0TG_MB_C_brd_V02_OCP.brd")
		(comment 1 "Grand Teton / footprint 4761 of 8354 (J18), pads 1-46 of 291")
	)
	(layers
		(0 "F.Cu" signal "TOP")
		(4 "In1.Cu" signal "GND")
		(6 "In2.Cu" signal "IN1")
		(8 "In3.Cu" signal "GND1")
		(10 "In4.Cu" signal "IN2")
		(12 "In5.Cu" signal "GND2")
		(14 "In6.Cu" signal "IN3")
		(16 "In7.Cu" signal "GND3")
		(18 "In8.Cu" signal "VCC")
		(20 "In9.Cu" signal "VCC1")
		(22 "In10.Cu" signal "GND4")
		(24 "In11.Cu" signal "IN4")
		(26 "In12.Cu" signal "GND5")
		(28 "In13.Cu" signal "IN5")
		(30 "In14.Cu" signal "GND6")
		(32 "In15.Cu" signal "IN6")
		(34 "In16.Cu" signal "GND7")
		(2 "B.Cu" signal "BOTTOM")
		(9 "F.Adhes" user "F.Adhesive")
		(11 "B.Adhes" user "B.Adhesive")
		(13 "F.Paste" user "Package Geometry/Pastemask Top")
		(15 "B.Paste" user "Package Geometry/Pastemask Bottom")
		(5 "F.SilkS" user "Ref Des/Silkscreen Top")
		(7 "B.SilkS" user "Ref Des/Silkscreen Bottom")
		(1 "F.Mask" user "Board Geometry/Soldermask Top")
		(3 "B.Mask" user "Board Geometry/Soldermask Bottom")
		(17 "Dwgs.User" user "User.Drawings")
		(19 "Cmts.User" user "User.Comments")
		(21 "Eco1.User" user "User.Eco1")
		(23 "Eco2.User" user "User.Eco2")
		(25 "Edge.Cuts" user "Board Geometry/Outline")
		(27 "Margin" user)
		(31 "F.CrtYd" user "Package Geometry/Place Bound Top")
		(29 "B.CrtYd" user "Package Geometry/Place Bound Bottom")
		(35 "F.Fab" user "Ref Des/Assembly Top")
		(33 "B.Fab" user "Ref Des/Assembly Bottom")
	)
	(footprint ""
		(layer "F.Cu")
		(at 429.506126 -255.560068 180)
		(property "Reference" "J18"
			(at 0.484632 -81.752948 0)
			(unlocked yes)
			(layer "F.SilkS")
			(effects
				(font
					(size 0.7874 0.5842)
					(thickness 0.1524)
				)
			)
		)
		(property "Value" ""
			(at 0 0 180)
			(layer "F.Fab")
			(effects
				(font
					(size 1.27 1.27)
				)
			)
		)
		(duplicate_pad_numbers_are_jumpers no)
		(pad "1" smd rect
			(at -2.050034 -63.324994 90)
			(size 0.519938 1.4986)
			(layers "F.Cu" "F.Mask" "F.Paste")
			(net "P12V_MEM_CPU0")
		)
		(pad "2" smd rect
			(at -2.050034 -62.47511 90)
			(size 0.519938 1.4986)
			(layers "F.Cu" "F.Mask" "F.Paste")
			(net "Net_2361")
		)
		(pad "3" smd rect
			(at -2.050034 -61.624972 90)
			(size 0.519938 1.4986)
			(layers "F.Cu" "F.Mask" "F.Paste")
			(net "P3V3_AUX")
		)
		(pad "4" smd rect
			(at -2.050034 -60.775088 90)
			(size 0.519938 1.4986)
			(layers "F.Cu" "F.Mask" "F.Paste")
			(net "I3C_SPD_DDRI_CPU0_SCL")
		)
		(pad "5" smd rect
			(at -2.050034 -59.92495 90)
			(size 0.519938 1.4986)
			(layers "F.Cu" "F.Mask" "F.Paste")
			(net "I3C_SPD_DDRI_CPU0_SDA")
		)
		(pad "6" smd rect
			(at -2.050034 -59.075066 90)
			(size 0.519938 1.4986)
			(layers "F.Cu" "F.Mask" "F.Paste")
			(net "GND")
		)
		(pad "7" smd rect
			(at -2.050034 -58.224928 90)
			(size 0.519938 1.4986)
			(layers "F.Cu" "F.Mask" "F.Paste")
			(net "M_I_CPU0_SA_DQ<0>")
		)
		(pad "8" smd rect
			(at -2.050034 -57.375044 90)
			(size 0.519938 1.4986)
			(layers "F.Cu" "F.Mask" "F.Paste")
			(net "GND")
		)
		(pad "9" smd rect
			(at -2.050034 -56.524906 90)
			(size 0.519938 1.4986)
			(layers "F.Cu" "F.Mask" "F.Paste")
			(net "M_I_CPU0_SA_DQ<1>")
		)
		(pad "10" smd rect
			(at -2.050034 -55.675022 90)
			(size 0.519938 1.4986)
			(layers "F.Cu" "F.Mask" "F.Paste")
			(net "GND")
		)
		(pad "11" smd rect
			(at -2.050034 -54.824884 90)
			(size 0.519938 1.4986)
			(layers "F.Cu" "F.Mask" "F.Paste")
			(net "M_I_CPU0_SA_DQS_DP<0>")
		)
		(pad "12" smd rect
			(at -2.050034 -53.975 90)
			(size 0.519938 1.4986)
			(layers "F.Cu" "F.Mask" "F.Paste")
			(net "M_I_CPU0_SA_DQS_DN<0>")
		)
		(pad "13" smd rect
			(at -2.050034 -53.125116 90)
			(size 0.519938 1.4986)
			(layers "F.Cu" "F.Mask" "F.Paste")
			(net "GND")
		)
		(pad "14" smd rect
			(at -2.050034 -52.274978 90)
			(size 0.519938 1.4986)
			(layers "F.Cu" "F.Mask" "F.Paste")
			(net "M_I_CPU0_SA_DQ<4>")
		)
		(pad "15" smd rect
			(at -2.050034 -51.425094 90)
			(size 0.519938 1.4986)
			(layers "F.Cu" "F.Mask" "F.Paste")
			(net "GND")
		)
		(pad "16" smd rect
			(at -2.050034 -50.574956 90)
			(size 0.519938 1.4986)
			(layers "F.Cu" "F.Mask" "F.Paste")
			(net "M_I_CPU0_SA_DQ<5>")
		)
		(pad "17" smd rect
			(at -2.050034 -49.725072 90)
			(size 0.519938 1.4986)
			(layers "F.Cu" "F.Mask" "F.Paste")
			(net "GND")
		)
		(pad "18" smd rect
			(at -2.050034 -48.874934 90)
			(size 0.519938 1.4986)
			(layers "F.Cu" "F.Mask" "F.Paste")
			(net "M_I_CPU0_SA_DQ<8>")
		)
		(pad "19" smd rect
			(at -2.050034 -48.02505 90)
			(size 0.519938 1.4986)
			(layers "F.Cu" "F.Mask" "F.Paste")
			(net "GND")
		)
		(pad "20" smd rect
			(at -2.050034 -47.174912 90)
			(size 0.519938 1.4986)
			(layers "F.Cu" "F.Mask" "F.Paste")
			(net "M_I_CPU0_SA_DQ<9>")
		)
		(pad "21" smd rect
			(at -2.050034 -46.325028 90)
			(size 0.519938 1.4986)
			(layers "F.Cu" "F.Mask" "F.Paste")
			(net "GND")
		)
		(pad "22" smd rect
			(at -2.050034 -45.47489 90)
			(size 0.519938 1.4986)
			(layers "F.Cu" "F.Mask" "F.Paste")
			(net "M_I_CPU0_SA_DQS_DP<1>")
		)
		(pad "23" smd rect
			(at -2.050034 -44.625006 90)
			(size 0.519938 1.4986)
			(layers "F.Cu" "F.Mask" "F.Paste")
			(net "M_I_CPU0_SA_DQS_DN<1>")
		)
		(pad "24" smd rect
			(at -2.050034 -43.775122 90)
			(size 0.519938 1.4986)
			(layers "F.Cu" "F.Mask" "F.Paste")
			(net "GND")
		)
		(pad "25" smd rect
			(at -2.050034 -42.924984 90)
			(size 0.519938 1.4986)
			(layers "F.Cu" "F.Mask" "F.Paste")
			(net "M_I_CPU0_SA_DQ<12>")
		)
		(pad "26" smd rect
			(at -2.050034 -42.0751 90)
			(size 0.519938 1.4986)
			(layers "F.Cu" "F.Mask" "F.Paste")
			(net "GND")
		)
		(pad "27" smd rect
			(at -2.050034 -41.224962 90)
			(size 0.519938 1.4986)
			(layers "F.Cu" "F.Mask" "F.Paste")
			(net "M_I_CPU0_SA_DQ<13>")
		)
		(pad "28" smd rect
			(at -2.050034 -40.375078 90)
			(size 0.519938 1.4986)
			(layers "F.Cu" "F.Mask" "F.Paste")
			(net "GND")
		)
		(pad "29" smd rect
			(at -2.050034 -39.52494 90)
			(size 0.519938 1.4986)
			(layers "F.Cu" "F.Mask" "F.Paste")
			(net "M_I_CPU0_SA_DQ<16>")
		)
		(pad "30" smd rect
			(at -2.050034 -38.675056 90)
			(size 0.519938 1.4986)
			(layers "F.Cu" "F.Mask" "F.Paste")
			(net "GND")
		)
		(pad "31" smd rect
			(at -2.050034 -37.824918 90)
			(size 0.519938 1.4986)
			(layers "F.Cu" "F.Mask" "F.Paste")
			(net "M_I_CPU0_SA_DQ<17>")
		)
		(pad "32" smd rect
			(at -2.050034 -36.975034 90)
			(size 0.519938 1.4986)
			(layers "F.Cu" "F.Mask" "F.Paste")
			(net "GND")
		)
		(pad "33" smd rect
			(at -2.050034 -36.124896 90)
			(size 0.519938 1.4986)
			(layers "F.Cu" "F.Mask" "F.Paste")
			(net "M_I_CPU0_SA_DQS_DP<2>")
		)
		(pad "34" smd rect
			(at -2.050034 -35.275012 90)
			(size 0.519938 1.4986)
			(layers "F.Cu" "F.Mask" "F.Paste")
			(net "M_I_CPU0_SA_DQS_DN<2>")
		)
		(pad "35" smd rect
			(at -2.050034 -34.425128 90)
			(size 0.519938 1.4986)
			(layers "F.Cu" "F.Mask" "F.Paste")
			(net "GND")
		)
		(pad "36" smd rect
			(at -2.050034 -33.57499 90)
			(size 0.519938 1.4986)
			(layers "F.Cu" "F.Mask" "F.Paste")
			(net "M_I_CPU0_SA_DQ<20>")
		)
		(pad "37" smd rect
			(at -2.050034 -32.725106 90)
			(size 0.519938 1.4986)
			(layers "F.Cu" "F.Mask" "F.Paste")
			(net "GND")
		)
		(pad "38" smd rect
			(at -2.050034 -31.874968 90)
			(size 0.519938 1.4986)
			(layers "F.Cu" "F.Mask" "F.Paste")
			(net "M_I_CPU0_SA_DQ<21>")
		)
		(pad "39" smd rect
			(at -2.050034 -31.025084 90)
			(size 0.519938 1.4986)
			(layers "F.Cu" "F.Mask" "F.Paste")
			(net "GND")
		)
		(pad "40" smd rect
			(at -2.050034 -30.174946 90)
			(size 0.519938 1.4986)
			(layers "F.Cu" "F.Mask" "F.Paste")
			(net "M_I_CPU0_SA_DQ<24>")
		)
		(pad "41" smd rect
			(at -2.050034 -29.325062 90)
			(size 0.519938 1.4986)
			(layers "F.Cu" "F.Mask" "F.Paste")
			(net "GND")
		)
		(pad "42" smd rect
			(at -2.050034 -28.474924 90)
			(size 0.519938 1.4986)
			(layers "F.Cu" "F.Mask" "F.Paste")
			(net "M_I_CPU0_SA_DQ<25>")
		)
		(pad "43" smd rect
			(at -2.050034 -27.62504 90)
			(size 0.519938 1.4986)
			(layers "F.Cu" "F.Mask" "F.Paste")
			(net "GND")
		)
		(pad "44" smd rect
			(at -2.050034 -26.774902 90)
			(size 0.519938 1.4986)
			(layers "F.Cu" "F.Mask" "F.Paste")
			(net "M_I_CPU0_SA_DQS_DP<3>")
		)
		(pad "45" smd rect
			(at -2.050034 -25.925018 90)
			(size 0.519938 1.4986)
			(layers "F.Cu" "F.Mask" "F.Paste")
			(net "M_I_CPU0_SA_DQS_DN<3>")
		)
		(pad "46" smd rect
			(at -2.050034 -25.07488 90)
			(size 0.519938 1.4986)
			(layers "F.Cu" "F.Mask" "F.Paste")
			(net "GND")
		)
	)
)
